(kicad_pcb
	(version 20260206)
	(generator "pcbnew")
	(generator_version "10.0")
	(general
		(thickness 1.6)
		(legacy_teardrops no)
	)
	(paper "A4")
	(title_block
		(title "01162023_DA0F0TEBIF0_F0T_Expander_BD_F_brd_V02_OCP.brd")
		(comment 1 "Grand Teton / footprints 4437-4442 of 9728")
	)
	(layers
		(0 "F.Cu" signal "TOP")
		(4 "In1.Cu" signal "GND")
		(6 "In2.Cu" signal "VCC")
		(8 "In3.Cu" signal "VCC1")
		(10 "In4.Cu" signal "GND1")
		(12 "In5.Cu" signal "IN1")
		(14 "In6.Cu" signal "GND2")
		(16 "In7.Cu" signal "IN2")
		(18 "In8.Cu" signal "GND3")
		(20 "In9.Cu" signal "IN3")
		(22 "In10.Cu" signal "GND4")
		(24 "In11.Cu" signal "IN4")
		(26 "In12.Cu" signal "GND5")
		(28 "In13.Cu" signal "IN5")
		(30 "In14.Cu" signal "GND6")
		(32 "In15.Cu" signal "IN6")
		(34 "In16.Cu" signal "GND7")
		(2 "B.Cu" signal "BOTTOM")
		(9 "F.Adhes" user "F.Adhesive")
		(11 "B.Adhes" user "B.Adhesive")
		(13 "F.Paste" user "Package Geometry/Pastemask Top")
		(15 "B.Paste" user "Package Geometry/Pastemask Bottom")
		(5 "F.SilkS" user "Ref Des/Silkscreen Top")
		(7 "B.SilkS" user "Ref Des/Silkscreen Bottom")
		(1 "F.Mask" user "Board Geometry/Soldermask Top")
		(3 "B.Mask" user "Board Geometry/Soldermask Bottom")
		(17 "Dwgs.User" user "User.Drawings")
		(19 "Cmts.User" user "User.Comments")
		(21 "Eco1.User" user "User.Eco1")
		(23 "Eco2.User" user "User.Eco2")
		(25 "Edge.Cuts" user "Board Geometry/Outline")
		(27 "Margin" user)
		(31 "F.CrtYd" user "Package Geometry/Place Bound Top")
		(29 "B.CrtYd" user "Package Geometry/Place Bound Bottom")
		(35 "F.Fab" user "Ref Des/Assembly Top")
		(33 "B.Fab" user "Ref Des/Assembly Bottom")
	)
	(footprint ""
		(layer "F.Cu")
		(at 169.940224 -32.848042 90)
		(property "Reference" "PC935"
			(at 0 0 90)
			(layer "F.SilkS")
			(hide yes)
			(effects
				(font
					(size 1.27 1.27)
				)
			)
		)
		(property "Value" ""
			(at 0 0 90)
			(layer "F.Fab")
			(effects
				(font
					(size 1.27 1.27)
				)
			)
		)
		(duplicate_pad_numbers_are_jumpers no)
		(fp_line
			(start 0.7874 -0.4064)
			(end 0.7874 0.4064)
			(stroke
				(width 0.1524)
				(type default)
			)
			(layer "F.SilkS")
		)
		(fp_line
			(start -0.7874 -0.4064)
			(end 0.7874 -0.4064)
			(stroke
				(width 0.1524)
				(type default)
			)
			(layer "F.SilkS")
		)
		(fp_line
			(start 0.7874 0.4064)
			(end -0.7874 0.4064)
			(stroke
				(width 0.1524)
				(type default)
			)
			(layer "F.SilkS")
		)
		(fp_line
			(start -0.7874 0.4064)
			(end -0.7874 -0.4064)
			(stroke
				(width 0.1524)
				(type default)
			)
			(layer "F.SilkS")
		)
		(fp_line
			(start -0.12065 -0.305054)
			(end -0.12065 -0.2794)
			(stroke
				(width 0.1)
				(type default)
			)
			(layer "F.Fab")
		)
		(fp_line
			(start -0.67945 -0.305054)
			(end -0.12065 -0.305054)
			(stroke
				(width 0.1)
				(type default)
			)
			(layer "F.Fab")
		)
		(fp_line
			(start 0.67945 -0.3048)
			(end 0.67945 0.3048)
			(stroke
				(width 0.1)
				(type default)
			)
			(layer "F.Fab")
		)
		(fp_line
			(start 0.12065 -0.3048)
			(end 0.67945 -0.3048)
			(stroke
				(width 0.1)
				(type default)
			)
			(layer "F.Fab")
		)
		(fp_line
			(start 0.12065 -0.2794)
			(end 0.12065 -0.3048)
			(stroke
				(width 0.1)
				(type default)
			)
			(layer "F.Fab")
		)
		(fp_line
			(start -0.12065 -0.2794)
			(end 0.12065 -0.2794)
			(stroke
				(width 0.1)
				(type default)
			)
			(layer "F.Fab")
		)
		(fp_line
			(start 0.120396 0.2794)
			(end -0.12065 0.2794)
			(stroke
				(width 0.1)
				(type default)
			)
			(layer "F.Fab")
		)
		(fp_line
			(start -0.12065 0.2794)
			(end -0.12065 0.3048)
			(stroke
				(width 0.1)
				(type default)
			)
			(layer "F.Fab")
		)
		(fp_line
			(start 0.67945 0.3048)
			(end 0.120396 0.3048)
			(stroke
				(width 0.1)
				(type default)
			)
			(layer "F.Fab")
		)
		(fp_line
			(start 0.120396 0.3048)
			(end 0.120396 0.2794)
			(stroke
				(width 0.1)
				(type default)
			)
			(layer "F.Fab")
		)
		(fp_line
			(start -0.12065 0.3048)
			(end -0.67945 0.3048)
			(stroke
				(width 0.1)
				(type default)
			)
			(layer "F.Fab")
		)
		(fp_line
			(start -0.67945 0.3048)
			(end -0.67945 -0.305054)
			(stroke
				(width 0.1)
				(type default)
			)
			(layer "F.Fab")
		)
		(pad "1" smd circle
			(at -0.40005 0 90)
			(size 0 0)
			(layers "F.Cu" "F.Mask" "F.Paste")
			(net "P3V3_SSD6_CO_DV_DT")
		)
		(pad "2" smd circle
			(at 0.40005 0 90)
			(size 0 0)
			(layers "F.Cu" "F.Mask" "F.Paste")
			(net "GND")
		)
	)
	(footprint ""
		(layer "F.Cu")
		(at 294.832024 -169.040302 -90)
		(property "Reference" "U32"
			(at 0.384302 -2.400046 90)
			(unlocked yes)
			(layer "F.SilkS")
			(effects
				(font
					(size 0.7874 0.5842)
					(thickness 0.1524)
				)
			)
		)
		(property "Value" ""
			(at 0 0 270)
			(layer "F.Fab")
			(effects
				(font
					(size 1.27 1.27)
				)
			)
		)
		(duplicate_pad_numbers_are_jumpers no)
		(fp_line
			(start -1.905 1.651)
			(end -1.905 -1.651)
			(stroke
				(width 0.1524)
				(type default)
			)
			(layer "F.SilkS")
		)
		(fp_line
			(start 1.905 1.651)
			(end -1.905 1.651)
			(stroke
				(width 0.1524)
				(type default)
			)
			(layer "F.SilkS")
		)
		(fp_line
			(start -1.905 -1.651)
			(end 1.905 -1.651)
			(stroke
				(width 0.1524)
				(type default)
			)
			(layer "F.SilkS")
		)
		(fp_line
			(start 1.905 -1.651)
			(end 1.905 1.651)
			(stroke
				(width 0.1524)
				(type default)
			)
			(layer "F.SilkS")
		)
		(fp_line
			(start -0.649986 1.524)
			(end -0.649986 1.169924)
			(stroke
				(width 0.1)
				(type default)
			)
			(layer "F.Fab")
		)
		(fp_line
			(start 0.6985 1.524)
			(end -0.649986 1.524)
			(stroke
				(width 0.1)
				(type default)
			)
			(layer "F.Fab")
		)
		(fp_line
			(start -1.249934 1.169924)
			(end -1.249934 0.729996)
			(stroke
				(width 0.1)
				(type default)
			)
			(layer "F.Fab")
		)
		(fp_line
			(start -0.649986 1.169924)
			(end -1.249934 1.169924)
			(stroke
				(width 0.1)
				(type default)
			)
			(layer "F.Fab")
		)
		(fp_line
			(start -1.249934 0.729996)
			(end -0.6985 0.729996)
			(stroke
				(width 0.1)
				(type default)
			)
			(layer "F.Fab")
		)
		(fp_line
			(start -0.6985 0.729996)
			(end -0.6985 -0.729996)
			(stroke
				(width 0.1)
				(type default)
			)
			(layer "F.Fab")
		)
		(fp_line
			(start 0.6985 0.219964)
			(end 0.6985 1.524)
			(stroke
				(width 0.1)
				(type default)
			)
			(layer "F.Fab")
		)
		(fp_line
			(start 1.249934 0.219964)
			(end 0.6985 0.219964)
			(stroke
				(width 0.1)
				(type default)
			)
			(layer "F.Fab")
		)
		(fp_line
			(start 0.6985 -0.219964)
			(end 1.249934 -0.219964)
			(stroke
				(width 0.1)
				(type default)
			)
			(layer "F.Fab")
		)
		(fp_line
			(start 1.249934 -0.219964)
			(end 1.249934 0.219964)
			(stroke
				(width 0.1)
				(type default)
			)
			(layer "F.Fab")
		)
		(fp_line
			(start -1.249934 -0.729996)
			(end -1.249934 -1.169924)
			(stroke
				(width 0.1)
				(type default)
			)
			(layer "F.Fab")
		)
		(fp_line
			(start -0.6985 -0.729996)
			(end -1.249934 -0.729996)
			(stroke
				(width 0.1)
				(type default)
			)
			(layer "F.Fab")
		)
		(fp_line
			(start -1.249934 -1.169924)
			(end -0.649986 -1.169924)
			(stroke
				(width 0.1)
				(type default)
			)
			(layer "F.Fab")
		)
		(fp_line
			(start -0.649986 -1.169924)
			(end -0.649986 -1.524)
			(stroke
				(width 0.1)
				(type default)
			)
			(layer "F.Fab")
		)
		(fp_line
			(start -0.649986 -1.524)
			(end 0.6985 -1.524)
			(stroke
				(width 0.1)
				(type default)
			)
			(layer "F.Fab")
		)
		(fp_line
			(start 0.6985 -1.524)
			(end 0.6985 -0.219964)
			(stroke
				(width 0.1)
				(type default)
			)
			(layer "F.Fab")
		)
		(pad "1" smd rect
			(at -1.1176 -1.016 180)
			(size 1.016 1.27)
			(layers "F.Cu" "F.Mask" "F.Paste")
			(net "HP_NIC4_PWRGD")
		)
		(pad "2" smd rect
			(at -1.1176 1.016 180)
			(size 1.016 1.27)
			(layers "F.Cu" "F.Mask" "F.Paste")
			(net "P3V3_NIC4")
		)
		(pad "3" smd rect
			(at 1.1176 0 180)
			(size 1.016 1.27)
			(layers "F.Cu" "F.Mask" "F.Paste")
			(net "GND")
		)
	)
	(footprint ""
		(layer "F.Cu")
		(at 247.886728 -112.139476 -90)
		(property "Reference" "PR7099"
			(at 0 0 270)
			(layer "F.SilkS")
			(hide yes)
			(effects
				(font
					(size 1.27 1.27)
				)
			)
		)
		(property "Value" ""
			(at 0 0 270)
			(layer "F.Fab")
			(effects
				(font
					(size 1.27 1.27)
				)
			)
		)
		(duplicate_pad_numbers_are_jumpers no)
		(fp_line
			(start -0.7874 0.4064)
			(end -0.7874 -0.4064)
			(stroke
				(width 0.1524)
				(type default)
			)
			(layer "F.SilkS")
		)
		(fp_line
			(start 0.7874 0.4064)
			(end -0.7874 0.4064)
			(stroke
				(width 0.1524)
				(type default)
			)
			(layer "F.SilkS")
		)
		(fp_line
			(start -0.7874 -0.4064)
			(end 0.7874 -0.4064)
			(stroke
				(width 0.1524)
				(type default)
			)
			(layer "F.SilkS")
		)
		(fp_line
			(start 0.7874 -0.4064)
			(end 0.7874 0.4064)
			(stroke
				(width 0.1524)
				(type default)
			)
			(layer "F.SilkS")
		)
		(fp_line
			(start -0.67945 0.3048)
			(end -0.67945 -0.305054)
			(stroke
				(width 0.1)
				(type default)
			)
			(layer "F.Fab")
		)
		(fp_line
			(start -0.12065 0.3048)
			(end -0.67945 0.3048)
			(stroke
				(width 0.1)
				(type default)
			)
			(layer "F.Fab")
		)
		(fp_line
			(start 0.120396 0.3048)
			(end 0.120396 0.2794)
			(stroke
				(width 0.1)
				(type default)
			)
			(layer "F.Fab")
		)
		(fp_line
			(start 0.67945 0.3048)
			(end 0.120396 0.3048)
			(stroke
				(width 0.1)
				(type default)
			)
			(layer "F.Fab")
		)
		(fp_line
			(start -0.12065 0.2794)
			(end -0.12065 0.3048)
			(stroke
				(width 0.1)
				(type default)
			)
			(layer "F.Fab")
		)
		(fp_line
			(start 0.120396 0.2794)
			(end -0.12065 0.2794)
			(stroke
				(width 0.1)
				(type default)
			)
			(layer "F.Fab")
		)
		(fp_line
			(start -0.12065 -0.2794)
			(end 0.12065 -0.2794)
			(stroke
				(width 0.1)
				(type default)
			)
			(layer "F.Fab")
		)
		(fp_line
			(start 0.12065 -0.2794)
			(end 0.12065 -0.3048)
			(stroke
				(width 0.1)
				(type default)
			)
			(layer "F.Fab")
		)
		(fp_line
			(start 0.12065 -0.3048)
			(end 0.67945 -0.3048)
			(stroke
				(width 0.1)
				(type default)
			)
			(layer "F.Fab")
		)
		(fp_line
			(start 0.67945 -0.3048)
			(end 0.67945 0.3048)
			(stroke
				(width 0.1)
				(type default)
			)
			(layer "F.Fab")
		)
		(fp_line
			(start -0.67945 -0.305054)
			(end -0.12065 -0.305054)
			(stroke
				(width 0.1)
				(type default)
			)
			(layer "F.Fab")
		)
		(fp_line
			(start -0.12065 -0.305054)
			(end -0.12065 -0.2794)
			(stroke
				(width 0.1)
				(type default)
			)
			(layer "F.Fab")
		)
		(pad "1" smd circle
			(at -0.40005 0 270)
			(size 0 0)
			(layers "F.Cu" "F.Mask" "F.Paste")
			(net "P3V3_NIC4_CO_MODE")
		)
		(pad "2" smd circle
			(at 0.40005 0 270)
			(size 0 0)
			(layers "F.Cu" "F.Mask" "F.Paste")
			(net "GND")
		)
	)
	(footprint ""
		(layer "F.Cu")
		(at 216.401396 -105.34904)
		(property "Reference" "C420"
			(at 0 0 0)
			(layer "F.SilkS")
			(hide yes)
			(effects
				(font
					(size 1.27 1.27)
				)
			)
		)
		(property "Value" ""
			(at 0 0 0)
			(layer "F.Fab")
			(effects
				(font
					(size 1.27 1.27)
				)
			)
		)
		(duplicate_pad_numbers_are_jumpers no)
		(fp_line
			(start -0.7874 -0.4064)
			(end 0.7874 -0.4064)
			(stroke
				(width 0.1524)
				(type default)
			)
			(layer "F.SilkS")
		)
		(fp_line
			(start -0.7874 0.4064)
			(end -0.7874 -0.4064)
			(stroke
				(width 0.1524)
				(type default)
			)
			(layer "F.SilkS")
		)
		(fp_line
			(start 0.7874 -0.4064)
			(end 0.7874 0.4064)
			(stroke
				(width 0.1524)
				(type default)
			)
			(layer "F.SilkS")
		)
		(fp_line
			(start 0.7874 0.4064)
			(end -0.7874 0.4064)
			(stroke
				(width 0.1524)
				(type default)
			)
			(layer "F.SilkS")
		)
		(fp_line
			(start -0.67945 -0.305054)
			(end -0.12065 -0.305054)
			(stroke
				(width 0.1)
				(type default)
			)
			(layer "F.Fab")
		)
		(fp_line
			(start -0.67945 0.3048)
			(end -0.67945 -0.305054)
			(stroke
				(width 0.1)
				(type default)
			)
			(layer "F.Fab")
		)
		(fp_line
			(start -0.12065 -0.305054)
			(end -0.12065 -0.2794)
			(stroke
				(width 0.1)
				(type default)
			)
			(layer "F.Fab")
		)
		(fp_line
			(start -0.12065 -0.2794)
			(end 0.12065 -0.2794)
			(stroke
				(width 0.1)
				(type default)
			)
			(layer "F.Fab")
		)
		(fp_line
			(start -0.12065 0.2794)
			(end -0.12065 0.3048)
			(stroke
				(width 0.1)
				(type default)
			)
			(layer "F.Fab")
		)
		(fp_line
			(start -0.12065 0.3048)
			(end -0.67945 0.3048)
			(stroke
				(width 0.1)
				(type default)
			)
			(layer "F.Fab")
		)
		(fp_line
			(start 0.120396 0.2794)
			(end -0.12065 0.2794)
			(stroke
				(width 0.1)
				(type default)
			)
			(layer "F.Fab")
		)
		(fp_line
			(start 0.120396 0.3048)
			(end 0.120396 0.2794)
			(stroke
				(width 0.1)
				(type default)
			)
			(layer "F.Fab")
		)
		(fp_line
			(start 0.12065 -0.3048)
			(end 0.67945 -0.3048)
			(stroke
				(width 0.1)
				(type default)
			)
			(layer "F.Fab")
		)
		(fp_line
			(start 0.12065 -0.2794)
			(end 0.12065 -0.3048)
			(stroke
				(width 0.1)
				(type default)
			)
			(layer "F.Fab")
		)
		(fp_line
			(start 0.67945 -0.3048)
			(end 0.67945 0.3048)
			(stroke
				(width 0.1)
				(type default)
			)
			(layer "F.Fab")
		)
		(fp_line
			(start 0.67945 0.3048)
			(end 0.120396 0.3048)
			(stroke
				(width 0.1)
				(type default)
			)
			(layer "F.Fab")
		)
		(pad "1" smd circle
			(at -0.40005 0)
			(size 0 0)
			(layers "F.Cu" "F.Mask" "F.Paste")
			(net "P12V_NIC3_VIN_P")
		)
		(pad "2" smd circle
			(at 0.40005 0)
			(size 0 0)
			(layers "F.Cu" "F.Mask" "F.Paste")
			(net "P12V_NIC3_VIN_N")
		)
	)
	(footprint ""
		(layer "F.Cu")
		(at 90.021156 -298.87291 -90)
		(property "Reference" "R4014"
			(at 0 0 270)
			(layer "F.SilkS")
			(hide yes)
			(effects
				(font
					(size 1.27 1.27)
				)
			)
		)
		(property "Value" ""
			(at 0 0 270)
			(layer "F.Fab")
			(effects
				(font
					(size 1.27 1.27)
				)
			)
		)
		(duplicate_pad_numbers_are_jumpers no)
		(fp_line
			(start -0.7874 0.4064)
			(end -0.7874 -0.4064)
			(stroke
				(width 0.1524)
				(type default)
			)
			(layer "F.SilkS")
		)
		(fp_line
			(start 0.7874 0.4064)
			(end -0.7874 0.4064)
			(stroke
				(width 0.1524)
				(type default)
			)
			(layer "F.SilkS")
		)
		(fp_line
			(start -0.7874 -0.4064)
			(end 0.7874 -0.4064)
			(stroke
				(width 0.1524)
				(type default)
			)
			(layer "F.SilkS")
		)
		(fp_line
			(start 0.7874 -0.4064)
			(end 0.7874 0.4064)
			(stroke
				(width 0.1524)
				(type default)
			)
			(layer "F.SilkS")
		)
		(fp_line
			(start -0.67945 0.3048)
			(end -0.67945 -0.305054)
			(stroke
				(width 0.1)
				(type default)
			)
			(layer "F.Fab")
		)
		(fp_line
			(start -0.12065 0.3048)
			(end -0.67945 0.3048)
			(stroke
				(width 0.1)
				(type default)
			)
			(layer "F.Fab")
		)
		(fp_line
			(start 0.120396 0.3048)
			(end 0.120396 0.2794)
			(stroke
				(width 0.1)
				(type default)
			)
			(layer "F.Fab")
		)
		(fp_line
			(start 0.67945 0.3048)
			(end 0.120396 0.3048)
			(stroke
				(width 0.1)
				(type default)
			)
			(layer "F.Fab")
		)
		(fp_line
			(start -0.12065 0.2794)
			(end -0.12065 0.3048)
			(stroke
				(width 0.1)
				(type default)
			)
			(layer "F.Fab")
		)
		(fp_line
			(start 0.120396 0.2794)
			(end -0.12065 0.2794)
			(stroke
				(width 0.1)
				(type default)
			)
			(layer "F.Fab")
		)
		(fp_line
			(start -0.12065 -0.2794)
			(end 0.12065 -0.2794)
			(stroke
				(width 0.1)
				(type default)
			)
			(layer "F.Fab")
		)
		(fp_line
			(start 0.12065 -0.2794)
			(end 0.12065 -0.3048)
			(stroke
				(width 0.1)
				(type default)
			)
			(layer "F.Fab")
		)
		(fp_line
			(start 0.12065 -0.3048)
			(end 0.67945 -0.3048)
			(stroke
				(width 0.1)
				(type default)
			)
			(layer "F.Fab")
		)
		(fp_line
			(start 0.67945 -0.3048)
			(end 0.67945 0.3048)
			(stroke
				(width 0.1)
				(type default)
			)
			(layer "F.Fab")
		)
		(fp_line
			(start -0.67945 -0.305054)
			(end -0.12065 -0.305054)
			(stroke
				(width 0.1)
				(type default)
			)
			(layer "F.Fab")
		)
		(fp_line
			(start -0.12065 -0.305054)
			(end -0.12065 -0.2794)
			(stroke
				(width 0.1)
				(type default)
			)
			(layer "F.Fab")
		)
		(pad "1" smd circle
			(at -0.40005 0 270)
			(size 0 0)
			(layers "F.Cu" "F.Mask" "F.Paste")
			(net "P1V8_PEX")
		)
		(pad "2" smd circle
			(at 0.40005 0 270)
			(size 0 0)
			(layers "F.Cu" "F.Mask" "F.Paste")
			(net "I2C_PEX0_HOST_R_SDA")
		)
	)
	(footprint ""
		(layer "F.Cu")
		(at 93.0656 -304.036476 90)
		(property "Reference" "R4180"
			(at 0 0 90)
			(layer "F.SilkS")
			(hide yes)
			(effects
				(font
					(size 1.27 1.27)
				)
			)
		)
		(property "Value" ""
			(at 0 0 90)
			(layer "F.Fab")
			(effects
				(font
					(size 1.27 1.27)
				)
			)
		)
		(duplicate_pad_numbers_are_jumpers no)
		(fp_line
			(start 0.7874 -0.4064)
			(end 0.7874 0.4064)
			(stroke
				(width 0.1524)
				(type default)
			)
			(layer "F.SilkS")
		)
		(fp_line
			(start -0.7874 -0.4064)
			(end 0.7874 -0.4064)
			(stroke
				(width 0.1524)
				(type default)
			)
			(layer "F.SilkS")
		)
		(fp_line
			(start 0.7874 0.4064)
			(end -0.7874 0.4064)
			(stroke
				(width 0.1524)
				(type default)
			)
			(layer "F.SilkS")
		)
		(fp_line
			(start -0.7874 0.4064)
			(end -0.7874 -0.4064)
			(stroke
				(width 0.1524)
				(type default)
			)
			(layer "F.SilkS")
		)
		(fp_line
			(start -0.12065 -0.305054)
			(end -0.12065 -0.2794)
			(stroke
				(width 0.1)
				(type default)
			)
			(layer "F.Fab")
		)
		(fp_line
			(start -0.67945 -0.305054)
			(end -0.12065 -0.305054)
			(stroke
				(width 0.1)
				(type default)
			)
			(layer "F.Fab")
		)
		(fp_line
			(start 0.67945 -0.3048)
			(end 0.67945 0.3048)
			(stroke
				(width 0.1)
				(type default)
			)
			(layer "F.Fab")
		)
		(fp_line
			(start 0.12065 -0.3048)
			(end 0.67945 -0.3048)
			(stroke
				(width 0.1)
				(type default)
			)
			(layer "F.Fab")
		)
		(fp_line
			(start 0.12065 -0.2794)
			(end 0.12065 -0.3048)
			(stroke
				(width 0.1)
				(type default)
			)
			(layer "F.Fab")
		)
		(fp_line
			(start -0.12065 -0.2794)
			(end 0.12065 -0.2794)
			(stroke
				(width 0.1)
				(type default)
			)
			(layer "F.Fab")
		)
		(fp_line
			(start 0.120396 0.2794)
			(end -0.12065 0.2794)
			(stroke
				(width 0.1)
				(type default)
			)
			(layer "F.Fab")
		)
		(fp_line
			(start -0.12065 0.2794)
			(end -0.12065 0.3048)
			(stroke
				(width 0.1)
				(type default)
			)
			(layer "F.Fab")
		)
		(fp_line
			(start 0.67945 0.3048)
			(end 0.120396 0.3048)
			(stroke
				(width 0.1)
				(type default)
			)
			(layer "F.Fab")
		)
		(fp_line
			(start 0.120396 0.3048)
			(end 0.120396 0.2794)
			(stroke
				(width 0.1)
				(type default)
			)
			(layer "F.Fab")
		)
		(fp_line
			(start -0.12065 0.3048)
			(end -0.67945 0.3048)
			(stroke
				(width 0.1)
				(type default)
			)
			(layer "F.Fab")
		)
		(fp_line
			(start -0.67945 0.3048)
			(end -0.67945 -0.305054)
			(stroke
				(width 0.1)
				(type default)
			)
			(layer "F.Fab")
		)
		(pad "1" smd circle
			(at -0.40005 0 90)
			(size 0 0)
			(layers "F.Cu" "F.Mask" "F.Paste")
			(net "GND")
		)
		(pad "2" smd circle
			(at 0.40005 0 90)
			(size 0 0)
			(layers "F.Cu" "F.Mask" "F.Paste")
			(net "PEX0_EXT_GPIO_LATCH_N")
		)
	)
)
